(kicad_pcb
	(version 20260206)
	(generator "pcbnew")
	(generator_version "10.0")
	(general
		(thickness 1.6)
		(legacy_teardrops no)
	)
	(paper "A4")
	(title_block
		(title "04192023_DAF0TMB3IC0_F0TG_MB_C_brd_V02_OCP.brd")
		(comment 1 "Grand Teton / footprints 7412-7418 of 8354")
	)
	(layers
		(0 "F.Cu" signal "TOP")
		(4 "In1.Cu" signal "GND")
		(6 "In2.Cu" signal "IN1")
		(8 "In3.Cu" signal "GND1")
		(10 "In4.Cu" signal "IN2")
		(12 "In5.Cu" signal "GND2")
		(14 "In6.Cu" signal "IN3")
		(16 "In7.Cu" signal "GND3")
		(18 "In8.Cu" signal "VCC")
		(20 "In9.Cu" signal "VCC1")
		(22 "In10.Cu" signal "GND4")
		(24 "In11.Cu" signal "IN4")
		(26 "In12.Cu" signal "GND5")
		(28 "In13.Cu" signal "IN5")
		(30 "In14.Cu" signal "GND6")
		(32 "In15.Cu" signal "IN6")
		(34 "In16.Cu" signal "GND7")
		(2 "B.Cu" signal "BOTTOM")
		(9 "F.Adhes" user "F.Adhesive")
		(11 "B.Adhes" user "B.Adhesive")
		(13 "F.Paste" user "Package Geometry/Pastemask Top")
		(15 "B.Paste" user "Package Geometry/Pastemask Bottom")
		(5 "F.SilkS" user "Ref Des/Silkscreen Top")
		(7 "B.SilkS" user "Ref Des/Silkscreen Bottom")
		(1 "F.Mask" user "Board Geometry/Soldermask Top")
		(3 "B.Mask" user "Board Geometry/Soldermask Bottom")
		(17 "Dwgs.User" user "User.Drawings")
		(19 "Cmts.User" user "User.Comments")
		(21 "Eco1.User" user "User.Eco1")
		(23 "Eco2.User" user "User.Eco2")
		(25 "Edge.Cuts" user "Board Geometry/Outline")
		(27 "Margin" user)
		(31 "F.CrtYd" user "Package Geometry/Place Bound Top")
		(29 "B.CrtYd" user "Package Geometry/Place Bound Bottom")
		(35 "F.Fab" user "Ref Des/Assembly Top")
		(33 "B.Fab" user "Ref Des/Assembly Bottom")
	)
	(footprint ""
		(layer "B.Cu")
		(at 165.1508 -424.60037 -90)
		(property "Reference" "R1510"
			(at 0 0 90)
			(layer "B.SilkS")
			(hide yes)
			(effects
				(font
					(size 1.27 1.27)
				)
				(justify mirror)
			)
		)
		(property "Value" ""
			(at 0 0 90)
			(layer "B.Fab")
			(effects
				(font
					(size 1.27 1.27)
				)
				(justify mirror)
			)
		)
		(duplicate_pad_numbers_are_jumpers no)
		(fp_line
			(start -0.32512 0.175006)
			(end 0.32512 0.175006)
			(stroke
				(width 0.1)
				(type default)
			)
			(layer "B.Fab")
		)
		(fp_line
			(start 0.32512 0.175006)
			(end 0.32512 -0.175006)
			(stroke
				(width 0.1)
				(type default)
			)
			(layer "B.Fab")
		)
		(fp_line
			(start -0.32512 -0.175006)
			(end -0.32512 0.175006)
			(stroke
				(width 0.1)
				(type default)
			)
			(layer "B.Fab")
		)
		(fp_line
			(start 0.32512 -0.175006)
			(end -0.32512 -0.175006)
			(stroke
				(width 0.1)
				(type default)
			)
			(layer "B.Fab")
		)
		(pad "1" smd rect
			(at 0.2667 0 90)
			(size 0.3048 0.381)
			(layers "B.Cu" "B.Mask" "B.Paste")
			(net "P1V8_CPU1_RT_1D")
		)
		(pad "2" smd rect
			(at -0.2667 0 270)
			(size 0.3048 0.381)
			(layers "B.Cu" "B.Mask" "B.Paste")
			(net "JTAG_TDI_RT_CPU1_P3")
		)
	)
	(footprint ""
		(layer "B.Cu")
		(at 64.595248 -168.86682 -90)
		(property "Reference" "PC130_6"
			(at 0 0 90)
			(layer "B.SilkS")
			(hide yes)
			(effects
				(font
					(size 1.27 1.27)
				)
				(justify mirror)
			)
		)
		(property "Value" ""
			(at 0 0 90)
			(layer "B.Fab")
			(effects
				(font
					(size 1.27 1.27)
				)
				(justify mirror)
			)
		)
		(duplicate_pad_numbers_are_jumpers no)
		(fp_line
			(start -1.524 0.762)
			(end 1.524 0.762)
			(stroke
				(width 0.1524)
				(type default)
			)
			(layer "B.SilkS")
		)
		(fp_line
			(start 1.524 0.762)
			(end 1.524 -0.762)
			(stroke
				(width 0.1524)
				(type default)
			)
			(layer "B.SilkS")
		)
		(fp_line
			(start -1.524 -0.762)
			(end -1.524 0.762)
			(stroke
				(width 0.1524)
				(type default)
			)
			(layer "B.SilkS")
		)
		(fp_line
			(start 1.524 -0.762)
			(end -1.524 -0.762)
			(stroke
				(width 0.1524)
				(type default)
			)
			(layer "B.SilkS")
		)
		(fp_line
			(start -1.1049 0.724916)
			(end -1.1049 -0.724916)
			(stroke
				(width 0.1)
				(type default)
			)
			(layer "B.Fab")
		)
		(fp_line
			(start 1.1049 0.724916)
			(end -1.1049 0.724916)
			(stroke
				(width 0.1)
				(type default)
			)
			(layer "B.Fab")
		)
		(fp_line
			(start -1.1049 -0.724916)
			(end 1.1049 -0.724916)
			(stroke
				(width 0.1)
				(type default)
			)
			(layer "B.Fab")
		)
		(fp_line
			(start 1.1049 -0.724916)
			(end 1.1049 0.724916)
			(stroke
				(width 0.1)
				(type default)
			)
			(layer "B.Fab")
		)
		(pad "1" smd rect
			(at 0.889 0 270)
			(size 1.016 1.27)
			(layers "B.Cu" "B.Mask" "B.Paste")
			(net "SW_P12V_AUX_PVDDCR_CPU0_P1_FLT")
		)
		(pad "2" smd rect
			(at -0.889 0 270)
			(size 1.016 1.27)
			(layers "B.Cu" "B.Mask" "B.Paste")
			(net "GND")
		)
	)
	(footprint ""
		(layer "B.Cu")
		(at 219.082112 -67.661028 -90)
		(property "Reference" "R3959"
			(at 0 0 90)
			(layer "B.SilkS")
			(hide yes)
			(effects
				(font
					(size 1.27 1.27)
				)
				(justify mirror)
			)
		)
		(property "Value" ""
			(at 0 0 90)
			(layer "B.Fab")
			(effects
				(font
					(size 1.27 1.27)
				)
				(justify mirror)
			)
		)
		(duplicate_pad_numbers_are_jumpers no)
		(fp_line
			(start -0.7874 0.4064)
			(end 0.7874 0.4064)
			(stroke
				(width 0.1524)
				(type default)
			)
			(layer "B.SilkS")
		)
		(fp_line
			(start 0.7874 0.4064)
			(end 0.7874 -0.4064)
			(stroke
				(width 0.1524)
				(type default)
			)
			(layer "B.SilkS")
		)
		(fp_line
			(start -0.7874 -0.4064)
			(end -0.7874 0.4064)
			(stroke
				(width 0.1524)
				(type default)
			)
			(layer "B.SilkS")
		)
		(fp_line
			(start 0.7874 -0.4064)
			(end -0.7874 -0.4064)
			(stroke
				(width 0.1524)
				(type default)
			)
			(layer "B.SilkS")
		)
		(fp_line
			(start -0.67945 0.3048)
			(end -0.120396 0.3048)
			(stroke
				(width 0.1)
				(type default)
			)
			(layer "B.Fab")
		)
		(fp_line
			(start -0.120396 0.3048)
			(end -0.120396 0.2794)
			(stroke
				(width 0.1)
				(type default)
			)
			(layer "B.Fab")
		)
		(fp_line
			(start 0.12065 0.3048)
			(end 0.67945 0.3048)
			(stroke
				(width 0.1)
				(type default)
			)
			(layer "B.Fab")
		)
		(fp_line
			(start 0.67945 0.3048)
			(end 0.67945 -0.305054)
			(stroke
				(width 0.1)
				(type default)
			)
			(layer "B.Fab")
		)
		(fp_line
			(start -0.120396 0.2794)
			(end 0.12065 0.2794)
			(stroke
				(width 0.1)
				(type default)
			)
			(layer "B.Fab")
		)
		(fp_line
			(start 0.12065 0.2794)
			(end 0.12065 0.3048)
			(stroke
				(width 0.1)
				(type default)
			)
			(layer "B.Fab")
		)
		(fp_line
			(start -0.12065 -0.2794)
			(end -0.12065 -0.3048)
			(stroke
				(width 0.1)
				(type default)
			)
			(layer "B.Fab")
		)
		(fp_line
			(start 0.12065 -0.2794)
			(end -0.12065 -0.2794)
			(stroke
				(width 0.1)
				(type default)
			)
			(layer "B.Fab")
		)
		(fp_line
			(start -0.67945 -0.3048)
			(end -0.67945 0.3048)
			(stroke
				(width 0.1)
				(type default)
			)
			(layer "B.Fab")
		)
		(fp_line
			(start -0.12065 -0.3048)
			(end -0.67945 -0.3048)
			(stroke
				(width 0.1)
				(type default)
			)
			(layer "B.Fab")
		)
		(fp_line
			(start 0.12065 -0.305054)
			(end 0.12065 -0.2794)
			(stroke
				(width 0.1)
				(type default)
			)
			(layer "B.Fab")
		)
		(fp_line
			(start 0.67945 -0.305054)
			(end 0.12065 -0.305054)
			(stroke
				(width 0.1)
				(type default)
			)
			(layer "B.Fab")
		)
		(pad "1" smd circle
			(at 0.40005 0 90)
			(size 0 0)
			(layers "B.Cu" "B.Mask" "B.Paste")
			(net "P3V3_E1S_UV_0_R")
		)
		(pad "2" smd circle
			(at -0.40005 0 90)
			(size 0 0)
			(layers "B.Cu" "B.Mask" "B.Paste")
			(net "P3V3_E1S_UV_0")
		)
	)
	(footprint ""
		(layer "B.Cu")
		(at 105.596182 -386.745988 -90)
		(property "Reference" "C200"
			(at 0 0 90)
			(layer "B.SilkS")
			(hide yes)
			(effects
				(font
					(size 1.27 1.27)
				)
				(justify mirror)
			)
		)
		(property "Value" ""
			(at 0 0 90)
			(layer "B.Fab")
			(effects
				(font
					(size 1.27 1.27)
				)
				(justify mirror)
			)
		)
		(duplicate_pad_numbers_are_jumpers no)
		(fp_line
			(start -0.7874 0.4064)
			(end 0.7874 0.4064)
			(stroke
				(width 0.1524)
				(type default)
			)
			(layer "B.SilkS")
		)
		(fp_line
			(start 0.7874 0.4064)
			(end 0.7874 -0.4064)
			(stroke
				(width 0.1524)
				(type default)
			)
			(layer "B.SilkS")
		)
		(fp_line
			(start -0.7874 -0.4064)
			(end -0.7874 0.4064)
			(stroke
				(width 0.1524)
				(type default)
			)
			(layer "B.SilkS")
		)
		(fp_line
			(start 0.7874 -0.4064)
			(end -0.7874 -0.4064)
			(stroke
				(width 0.1524)
				(type default)
			)
			(layer "B.SilkS")
		)
		(fp_line
			(start -0.67945 0.3048)
			(end -0.120396 0.3048)
			(stroke
				(width 0.1)
				(type default)
			)
			(layer "B.Fab")
		)
		(fp_line
			(start -0.120396 0.3048)
			(end -0.120396 0.2794)
			(stroke
				(width 0.1)
				(type default)
			)
			(layer "B.Fab")
		)
		(fp_line
			(start 0.12065 0.3048)
			(end 0.67945 0.3048)
			(stroke
				(width 0.1)
				(type default)
			)
			(layer "B.Fab")
		)
		(fp_line
			(start 0.67945 0.3048)
			(end 0.67945 -0.305054)
			(stroke
				(width 0.1)
				(type default)
			)
			(layer "B.Fab")
		)
		(fp_line
			(start -0.120396 0.2794)
			(end 0.12065 0.2794)
			(stroke
				(width 0.1)
				(type default)
			)
			(layer "B.Fab")
		)
		(fp_line
			(start 0.12065 0.2794)
			(end 0.12065 0.3048)
			(stroke
				(width 0.1)
				(type default)
			)
			(layer "B.Fab")
		)
		(fp_line
			(start -0.12065 -0.2794)
			(end -0.12065 -0.3048)
			(stroke
				(width 0.1)
				(type default)
			)
			(layer "B.Fab")
		)
		(fp_line
			(start 0.12065 -0.2794)
			(end -0.12065 -0.2794)
			(stroke
				(width 0.1)
				(type default)
			)
			(layer "B.Fab")
		)
		(fp_line
			(start -0.67945 -0.3048)
			(end -0.67945 0.3048)
			(stroke
				(width 0.1)
				(type default)
			)
			(layer "B.Fab")
		)
		(fp_line
			(start -0.12065 -0.3048)
			(end -0.67945 -0.3048)
			(stroke
				(width 0.1)
				(type default)
			)
			(layer "B.Fab")
		)
		(fp_line
			(start 0.12065 -0.305054)
			(end 0.12065 -0.2794)
			(stroke
				(width 0.1)
				(type default)
			)
			(layer "B.Fab")
		)
		(fp_line
			(start 0.67945 -0.305054)
			(end 0.12065 -0.305054)
			(stroke
				(width 0.1)
				(type default)
			)
			(layer "B.Fab")
		)
		(pad "1" smd circle
			(at 0.40005 0 90)
			(size 0 0)
			(layers "B.Cu" "B.Mask" "B.Paste")
			(net "P1V8_CPU1_RT_1D")
		)
		(pad "2" smd circle
			(at -0.40005 0 90)
			(size 0 0)
			(layers "B.Cu" "B.Mask" "B.Paste")
			(net "GND")
		)
	)
	(footprint ""
		(layer "B.Cu")
		(at 237.617 -250.571)
		(property "Reference" "R363"
			(at 0 0 0)
			(layer "B.SilkS")
			(hide yes)
			(effects
				(font
					(size 1.27 1.27)
				)
				(justify mirror)
			)
		)
		(property "Value" ""
			(at 0 0 0)
			(layer "B.Fab")
			(effects
				(font
					(size 1.27 1.27)
				)
				(justify mirror)
			)
		)
		(duplicate_pad_numbers_are_jumpers no)
		(fp_line
			(start -0.7874 -0.4064)
			(end -0.7874 0.4064)
			(stroke
				(width 0.1524)
				(type default)
			)
			(layer "B.SilkS")
		)
		(fp_line
			(start -0.7874 0.4064)
			(end 0.7874 0.4064)
			(stroke
				(width 0.1524)
				(type default)
			)
			(layer "B.SilkS")
		)
		(fp_line
			(start 0.7874 -0.4064)
			(end -0.7874 -0.4064)
			(stroke
				(width 0.1524)
				(type default)
			)
			(layer "B.SilkS")
		)
		(fp_line
			(start 0.7874 0.4064)
			(end 0.7874 -0.4064)
			(stroke
				(width 0.1524)
				(type default)
			)
			(layer "B.SilkS")
		)
		(fp_line
			(start -0.67945 -0.3048)
			(end -0.67945 0.3048)
			(stroke
				(width 0.1)
				(type default)
			)
			(layer "B.Fab")
		)
		(fp_line
			(start -0.67945 0.3048)
			(end -0.120396 0.3048)
			(stroke
				(width 0.1)
				(type default)
			)
			(layer "B.Fab")
		)
		(fp_line
			(start -0.12065 -0.3048)
			(end -0.67945 -0.3048)
			(stroke
				(width 0.1)
				(type default)
			)
			(layer "B.Fab")
		)
		(fp_line
			(start -0.12065 -0.2794)
			(end -0.12065 -0.3048)
			(stroke
				(width 0.1)
				(type default)
			)
			(layer "B.Fab")
		)
		(fp_line
			(start -0.120396 0.2794)
			(end 0.12065 0.2794)
			(stroke
				(width 0.1)
				(type default)
			)
			(layer "B.Fab")
		)
		(fp_line
			(start -0.120396 0.3048)
			(end -0.120396 0.2794)
			(stroke
				(width 0.1)
				(type default)
			)
			(layer "B.Fab")
		)
		(fp_line
			(start 0.12065 -0.305054)
			(end 0.12065 -0.2794)
			(stroke
				(width 0.1)
				(type default)
			)
			(layer "B.Fab")
		)
		(fp_line
			(start 0.12065 -0.2794)
			(end -0.12065 -0.2794)
			(stroke
				(width 0.1)
				(type default)
			)
			(layer "B.Fab")
		)
		(fp_line
			(start 0.12065 0.2794)
			(end 0.12065 0.3048)
			(stroke
				(width 0.1)
				(type default)
			)
			(layer "B.Fab")
		)
		(fp_line
			(start 0.12065 0.3048)
			(end 0.67945 0.3048)
			(stroke
				(width 0.1)
				(type default)
			)
			(layer "B.Fab")
		)
		(fp_line
			(start 0.67945 -0.305054)
			(end 0.12065 -0.305054)
			(stroke
				(width 0.1)
				(type default)
			)
			(layer "B.Fab")
		)
		(fp_line
			(start 0.67945 0.3048)
			(end 0.67945 -0.305054)
			(stroke
				(width 0.1)
				(type default)
			)
			(layer "B.Fab")
		)
		(pad "1" smd circle
			(at 0.40005 0 180)
			(size 0 0)
			(layers "B.Cu" "B.Mask" "B.Paste")
			(net "PVDD11_S3_P0")
		)
		(pad "2" smd circle
			(at -0.40005 0 180)
			(size 0 0)
			(layers "B.Cu" "B.Mask" "B.Paste")
			(net "SMB_APML_CPU0_SCL")
		)
	)
	(footprint ""
		(layer "B.Cu")
		(at 182.948834 -344.199972 -90)
		(property "Reference" "PC525"
			(at 7.610856 -3.388106 270)
			(unlocked yes)
			(layer "B.SilkS")
			(effects
				(font
					(size 0.7874 0.5842)
					(thickness 0.1524)
				)
				(justify left mirror)
			)
		)
		(property "Value" ""
			(at 0 0 90)
			(layer "B.Fab")
			(effects
				(font
					(size 1.27 1.27)
				)
				(justify mirror)
			)
		)
		(duplicate_pad_numbers_are_jumpers no)
		(fp_line
			(start -4.533392 2.249932)
			(end 4.533392 2.249932)
			(stroke
				(width 0.1524)
				(type default)
			)
			(layer "B.SilkS")
		)
		(fp_line
			(start 4.533392 2.249932)
			(end 4.533392 -2.249932)
			(stroke
				(width 0.1524)
				(type default)
			)
			(layer "B.SilkS")
		)
		(fp_line
			(start -4.533392 -2.249932)
			(end -4.533392 2.249932)
			(stroke
				(width 0.1524)
				(type default)
			)
			(layer "B.SilkS")
		)
		(fp_line
			(start 4.533392 -2.249932)
			(end -4.533392 -2.249932)
			(stroke
				(width 0.1524)
				(type default)
			)
			(layer "B.SilkS")
		)
		(fp_rect
			(start 5.39242 2.326132)
			(end 4.533392 -2.326132)
			(stroke
				(width 0)
				(type default)
			)
			(fill yes)
			(layer "B.SilkS")
		)
		(fp_line
			(start -3.750056 2.249932)
			(end 3.750056 2.249932)
			(stroke
				(width 0.1)
				(type default)
			)
			(layer "B.Fab")
		)
		(fp_line
			(start 3.750056 2.249932)
			(end 3.750056 -2.249932)
			(stroke
				(width 0.1)
				(type default)
			)
			(layer "B.Fab")
		)
		(fp_line
			(start -3.750056 -2.249932)
			(end -3.750056 2.249932)
			(stroke
				(width 0.1)
				(type default)
			)
			(layer "B.Fab")
		)
		(fp_line
			(start 3.750056 -2.249932)
			(end -3.750056 -2.249932)
			(stroke
				(width 0.1)
				(type default)
			)
			(layer "B.Fab")
		)
		(fp_text user "-"
			(at -4.658868 2.486914 270)
			(unlocked yes)
			(layer "B.SilkS")
			(effects
				(font
					(size 1.905 1.4224)
					(thickness 0.1524)
				)
				(justify left mirror)
			)
		)
		(fp_text user "+"
			(at 6.322314 0.786384 180)
			(unlocked yes)
			(layer "B.SilkS")
			(effects
				(font
					(size 1.905 1.4224)
					(thickness 0.1524)
				)
				(justify left mirror)
			)
		)
		(fp_text user "+"
			(at 6.322314 0.786384 180)
			(unlocked yes)
			(layer "B.Fab")
			(effects
				(font
					(size 1.905 1.4224)
					(thickness 0.1524)
				)
				(justify left mirror)
			)
		)
		(fp_text user "-"
			(at -4.8514 -0.14605 270)
			(unlocked yes)
			(layer "B.Fab")
			(effects
				(font
					(size 1.905 1.4224)
					(thickness 0.1524)
				)
				(justify left mirror)
			)
		)
		(pad "1" smd rect
			(at 3.199892 0 90)
			(size 2.413 2.8194)
			(layers "B.Cu" "B.Mask" "B.Paste")
			(net "PVDD11_S3_P1")
		)
		(pad "2" smd rect
			(at -3.199892 0 90)
			(size 2.413 2.8194)
			(layers "B.Cu" "B.Mask" "B.Paste")
			(net "GND")
		)
	)
	(footprint ""
		(layer "B.Cu")
		(at 408.45867 -167.53459 90)
		(property "Reference" "PR357"
			(at 0 0 90)
			(layer "B.SilkS")
			(hide yes)
			(effects
				(font
					(size 1.27 1.27)
				)
				(justify mirror)
			)
		)
		(property "Value" ""
			(at 0 0 90)
			(layer "B.Fab")
			(effects
				(font
					(size 1.27 1.27)
				)
				(justify mirror)
			)
		)
		(duplicate_pad_numbers_are_jumpers no)
		(fp_line
			(start 0.7874 -0.4064)
			(end -0.7874 -0.4064)
			(stroke
				(width 0.1524)
				(type default)
			)
			(layer "B.SilkS")
		)
		(fp_line
			(start -0.7874 -0.4064)
			(end -0.7874 0.4064)
			(stroke
				(width 0.1524)
				(type default)
			)
			(layer "B.SilkS")
		)
		(fp_line
			(start 0.7874 0.4064)
			(end 0.7874 -0.4064)
			(stroke
				(width 0.1524)
				(type default)
			)
			(layer "B.SilkS")
		)
		(fp_line
			(start -0.7874 0.4064)
			(end 0.7874 0.4064)
			(stroke
				(width 0.1524)
				(type default)
			)
			(layer "B.SilkS")
		)
		(fp_line
			(start 0.67945 -0.305054)
			(end 0.12065 -0.305054)
			(stroke
				(width 0.1)
				(type default)
			)
			(layer "B.Fab")
		)
		(fp_line
			(start 0.12065 -0.305054)
			(end 0.12065 -0.2794)
			(stroke
				(width 0.1)
				(type default)
			)
			(layer "B.Fab")
		)
		(fp_line
			(start -0.12065 -0.3048)
			(end -0.67945 -0.3048)
			(stroke
				(width 0.1)
				(type default)
			)
			(layer "B.Fab")
		)
		(fp_line
			(start -0.67945 -0.3048)
			(end -0.67945 0.3048)
			(stroke
				(width 0.1)
				(type default)
			)
			(layer "B.Fab")
		)
		(fp_line
			(start 0.12065 -0.2794)
			(end -0.12065 -0.2794)
			(stroke
				(width 0.1)
				(type default)
			)
			(layer "B.Fab")
		)
		(fp_line
			(start -0.12065 -0.2794)
			(end -0.12065 -0.3048)
			(stroke
				(width 0.1)
				(type default)
			)
			(layer "B.Fab")
		)
		(fp_line
			(start 0.12065 0.2794)
			(end 0.12065 0.3048)
			(stroke
				(width 0.1)
				(type default)
			)
			(layer "B.Fab")
		)
		(fp_line
			(start -0.120396 0.2794)
			(end 0.12065 0.2794)
			(stroke
				(width 0.1)
				(type default)
			)
			(layer "B.Fab")
		)
		(fp_line
			(start 0.67945 0.3048)
			(end 0.67945 -0.305054)
			(stroke
				(width 0.1)
				(type default)
			)
			(layer "B.Fab")
		)
		(fp_line
			(start 0.12065 0.3048)
			(end 0.67945 0.3048)
			(stroke
				(width 0.1)
				(type default)
			)
			(layer "B.Fab")
		)
		(fp_line
			(start -0.120396 0.3048)
			(end -0.120396 0.2794)
			(stroke
				(width 0.1)
				(type default)
			)
			(layer "B.Fab")
		)
		(fp_line
			(start -0.67945 0.3048)
			(end -0.120396 0.3048)
			(stroke
				(width 0.1)
				(type default)
			)
			(layer "B.Fab")
		)
		(pad "1" smd circle
			(at 0.40005 0 270)
			(size 0 0)
			(layers "B.Cu" "B.Mask" "B.Paste")
			(net "PVDDCR_CPU0_P0_PVCC")
		)
		(pad "2" smd circle
			(at -0.40005 0 270)
			(size 0 0)
			(layers "B.Cu" "B.Mask" "B.Paste")
			(net "PVDDCR_SOC_P0_VCC2")
		)
	)
)
